# T6G (Grand Teton) — schematic netlist excerpt (pin names and nets, part order shuffled) for the footprints in the layout excerpt that follows; sources: Cadence DE-HDL packaged netlist, KiCad conversion of 04192023_DAF0TMB3IC0_F0TG_MB_C_brd_V02_OCP.brd

R100  Q_RES  1K 1% EMPTY  pkg 0402LF  page 96 : A = P3V3 ; B = PWRGD_CHK_CPU0_DIMM
R1517  Q_RES  33.2 1% CHIP  pkg 0402LF  page 151 : A = SMB_HOST_CLK_3V3AUX_SDA ; B = SMB_HOST_CLK_3V3AUX_SDA_R1
R716  Q_RES  4.7K 5% EMPTY  pkg 0201LF  page 320 : A = P1V8_CPU1_RT_1D ; B = TEST0_RT_CPU1_P0

(kicad_pcb
	(version 20260206)
	(generator "pcbnew")
	(generator_version "10.0")
	(general
		(thickness 1.6)
		(legacy_teardrops no)
	)
	(paper "A4")
	(title_block
		(title "04192023_DAF0TMB3IC0_F0TG_MB_C_brd_V02_OCP.brd")
		(comment 1 "Grand Teton / footprints 7919-7921 of 8354")
	)
	(layers
		(0 "F.Cu" signal "TOP")
		(4 "In1.Cu" signal "GND")
		(6 "In2.Cu" signal "IN1")
		(8 "In3.Cu" signal "GND1")
		(10 "In4.Cu" signal "IN2")
		(12 "In5.Cu" signal "GND2")
		(14 "In6.Cu" signal "IN3")
		(16 "In7.Cu" signal "GND3")
		(18 "In8.Cu" signal "VCC")
		(20 "In9.Cu" signal "VCC1")
		(22 "In10.Cu" signal "GND4")
		(24 "In11.Cu" signal "IN4")
		(26 "In12.Cu" signal "GND5")
		(28 "In13.Cu" signal "IN5")
		(30 "In14.Cu" signal "GND6")
		(32 "In15.Cu" signal "IN6")
		(34 "In16.Cu" signal "GND7")
		(2 "B.Cu" signal "BOTTOM")
		(9 "F.Adhes" user "F.Adhesive")
		(11 "B.Adhes" user "B.Adhesive")
		(13 "F.Paste" user "Package Geometry/Pastemask Top")
		(15 "B.Paste" user "Package Geometry/Pastemask Bottom")
		(5 "F.SilkS" user "Ref Des/Silkscreen Top")
		(7 "B.SilkS" user "Ref Des/Silkscreen Bottom")
		(1 "F.Mask" user "Board Geometry/Soldermask Top")
		(3 "B.Mask" user "Board Geometry/Soldermask Bottom")
		(17 "Dwgs.User" user "User.Drawings")
		(19 "Cmts.User" user "User.Comments")
		(21 "Eco1.User" user "User.Eco1")
		(23 "Eco2.User" user "User.Eco2")
		(25 "Edge.Cuts" user "Board Geometry/Outline")
		(27 "Margin" user)
		(31 "F.CrtYd" user "Package Geometry/Place Bound Top")
		(29 "B.CrtYd" user "Package Geometry/Place Bound Bottom")
		(35 "F.Fab" user "Ref Des/Assembly Top")
		(33 "B.Fab" user "Ref Des/Assembly Bottom")
	)
	(footprint ""
		(layer "B.Cu")
		(at 443.29985 -193.99631)
		(property "Reference" "R100"
			(at 0 0 0)
			(layer "B.SilkS")
			(hide yes)
			(effects
				(font
					(size 1.27 1.27)
				)
				(justify mirror)
			)
		)
		(property "Value" ""
			(at 0 0 0)
			(layer "B.Fab")
			(effects
				(font
					(size 1.27 1.27)
				)
				(justify mirror)
			)
		)
		(duplicate_pad_numbers_are_jumpers no)
		(fp_line
			(start -0.7874 -0.4064)
			(end -0.7874 0.4064)
			(stroke
				(width 0.1524)
				(type default)
			)
			(layer "B.SilkS")
		)
		(fp_line
			(start -0.7874 0.4064)
			(end 0.7874 0.4064)
			(stroke
				(width 0.1524)
				(type default)
			)
			(layer "B.SilkS")
		)
		(fp_line
			(start 0.7874 -0.4064)
			(end -0.7874 -0.4064)
			(stroke
				(width 0.1524)
				(type default)
			)
			(layer "B.SilkS")
		)
		(fp_line
			(start 0.7874 0.4064)
			(end 0.7874 -0.4064)
			(stroke
				(width 0.1524)
				(type default)
			)
			(layer "B.SilkS")
		)
		(fp_line
			(start -0.67945 -0.3048)
			(end -0.67945 0.3048)
			(stroke
				(width 0.1)
				(type default)
			)
			(layer "B.Fab")
		)
		(fp_line
			(start -0.67945 0.3048)
			(end -0.120396 0.3048)
			(stroke
				(width 0.1)
				(type default)
			)
			(layer "B.Fab")
		)
		(fp_line
			(start -0.12065 -0.3048)
			(end -0.67945 -0.3048)
			(stroke
				(width 0.1)
				(type default)
			)
			(layer "B.Fab")
		)
		(fp_line
			(start -0.12065 -0.2794)
			(end -0.12065 -0.3048)
			(stroke
				(width 0.1)
				(type default)
			)
			(layer "B.Fab")
		)
		(fp_line
			(start -0.120396 0.2794)
			(end 0.12065 0.2794)
			(stroke
				(width 0.1)
				(type default)
			)
			(layer "B.Fab")
		)
		(fp_line
			(start -0.120396 0.3048)
			(end -0.120396 0.2794)
			(stroke
				(width 0.1)
				(type default)
			)
			(layer "B.Fab")
		)
		(fp_line
			(start 0.12065 -0.305054)
			(end 0.12065 -0.2794)
			(stroke
				(width 0.1)
				(type default)
			)
			(layer "B.Fab")
		)
		(fp_line
			(start 0.12065 -0.2794)
			(end -0.12065 -0.2794)
			(stroke
				(width 0.1)
				(type default)
			)
			(layer "B.Fab")
		)
		(fp_line
			(start 0.12065 0.2794)
			(end 0.12065 0.3048)
			(stroke
				(width 0.1)
				(type default)
			)
			(layer "B.Fab")
		)
		(fp_line
			(start 0.12065 0.3048)
			(end 0.67945 0.3048)
			(stroke
				(width 0.1)
				(type default)
			)
			(layer "B.Fab")
		)
		(fp_line
			(start 0.67945 -0.305054)
			(end 0.12065 -0.305054)
			(stroke
				(width 0.1)
				(type default)
			)
			(layer "B.Fab")
		)
		(fp_line
			(start 0.67945 0.3048)
			(end 0.67945 -0.305054)
			(stroke
				(width 0.1)
				(type default)
			)
			(layer "B.Fab")
		)
		(pad "1" smd circle
			(at 0.40005 0 180)
			(size 0 0)
			(layers "B.Cu" "B.Mask" "B.Paste")
			(net "P3V3")
		)
		(pad "2" smd circle
			(at -0.40005 0 180)
			(size 0 0)
			(layers "B.Cu" "B.Mask" "B.Paste")
			(net "PWRGD_CHK_CPU0_DIMM")
		)
	)
	(footprint ""
		(layer "B.Cu")
		(at 103.125524 -414.329626 180)
		(property "Reference" "R1517"
			(at 0 0 0)
			(layer "B.SilkS")
			(hide yes)
			(effects
				(font
					(size 1.27 1.27)
				)
				(justify mirror)
			)
		)
		(property "Value" ""
			(at 0 0 0)
			(layer "B.Fab")
			(effects
				(font
					(size 1.27 1.27)
				)
				(justify mirror)
			)
		)
		(duplicate_pad_numbers_are_jumpers no)
		(fp_line
			(start 0.7874 0.4064)
			(end 0.7874 -0.4064)
			(stroke
				(width 0.1524)
				(type default)
			)
			(layer "B.SilkS")
		)
		(fp_line
			(start 0.7874 -0.4064)
			(end -0.7874 -0.4064)
			(stroke
				(width 0.1524)
				(type default)
			)
			(layer "B.SilkS")
		)
		(fp_line
			(start -0.7874 0.4064)
			(end 0.7874 0.4064)
			(stroke
				(width 0.1524)
				(type default)
			)
			(layer "B.SilkS")
		)
		(fp_line
			(start -0.7874 -0.4064)
			(end -0.7874 0.4064)
			(stroke
				(width 0.1524)
				(type default)
			)
			(layer "B.SilkS")
		)
		(fp_line
			(start 0.67945 0.3048)
			(end 0.67945 -0.305054)
			(stroke
				(width 0.1)
				(type default)
			)
			(layer "B.Fab")
		)
		(fp_line
			(start 0.67945 -0.305054)
			(end 0.12065 -0.305054)
			(stroke
				(width 0.1)
				(type default)
			)
			(layer "B.Fab")
		)
		(fp_line
			(start 0.12065 0.3048)
			(end 0.67945 0.3048)
			(stroke
				(width 0.1)
				(type default)
			)
			(layer "B.Fab")
		)
		(fp_line
			(start 0.12065 0.2794)
			(end 0.12065 0.3048)
			(stroke
				(width 0.1)
				(type default)
			)
			(layer "B.Fab")
		)
		(fp_line
			(start 0.12065 -0.2794)
			(end -0.12065 -0.2794)
			(stroke
				(width 0.1)
				(type default)
			)
			(layer "B.Fab")
		)
		(fp_line
			(start 0.12065 -0.305054)
			(end 0.12065 -0.2794)
			(stroke
				(width 0.1)
				(type default)
			)
			(layer "B.Fab")
		)
		(fp_line
			(start -0.120396 0.3048)
			(end -0.120396 0.2794)
			(stroke
				(width 0.1)
				(type default)
			)
			(layer "B.Fab")
		)
		(fp_line
			(start -0.120396 0.2794)
			(end 0.12065 0.2794)
			(stroke
				(width 0.1)
				(type default)
			)
			(layer "B.Fab")
		)
		(fp_line
			(start -0.12065 -0.2794)
			(end -0.12065 -0.3048)
			(stroke
				(width 0.1)
				(type default)
			)
			(layer "B.Fab")
		)
		(fp_line
			(start -0.12065 -0.3048)
			(end -0.67945 -0.3048)
			(stroke
				(width 0.1)
				(type default)
			)
			(layer "B.Fab")
		)
		(fp_line
			(start -0.67945 0.3048)
			(end -0.120396 0.3048)
			(stroke
				(width 0.1)
				(type default)
			)
			(layer "B.Fab")
		)
		(fp_line
			(start -0.67945 -0.3048)
			(end -0.67945 0.3048)
			(stroke
				(width 0.1)
				(type default)
			)
			(layer "B.Fab")
		)
		(pad "1" smd circle
			(at 0.40005 0)
			(size 0 0)
			(layers "B.Cu" "B.Mask" "B.Paste")
			(net "SMB_HOST_CLK_3V3AUX_SDA")
		)
		(pad "2" smd circle
			(at -0.40005 0)
			(size 0 0)
			(layers "B.Cu" "B.Mask" "B.Paste")
			(net "SMB_HOST_CLK_3V3AUX_SDA_R1")
		)
	)
	(footprint ""
		(layer "B.Cu")
		(at 43.265852 -386.72516 180)
		(property "Reference" "R716"
			(at 0 0 0)
			(layer "B.SilkS")
			(hide yes)
			(effects
				(font
					(size 1.27 1.27)
				)
				(justify mirror)
			)
		)
		(property "Value" ""
			(at 0 0 0)
			(layer "B.Fab")
			(effects
				(font
					(size 1.27 1.27)
				)
				(justify mirror)
			)
		)
		(duplicate_pad_numbers_are_jumpers no)
		(fp_line
			(start 0.32512 0.175006)
			(end 0.32512 -0.175006)
			(stroke
				(width 0.1)
				(type default)
			)
			(layer "B.Fab")
		)
		(fp_line
			(start 0.32512 -0.175006)
			(end -0.32512 -0.175006)
			(stroke
				(width 0.1)
				(type default)
			)
			(layer "B.Fab")
		)
		(fp_line
			(start -0.32512 0.175006)
			(end 0.32512 0.175006)
			(stroke
				(width 0.1)
				(type default)
			)
			(layer "B.Fab")
		)
		(fp_line
			(start -0.32512 -0.175006)
			(end -0.32512 0.175006)
			(stroke
				(width 0.1)
				(type default)
			)
			(layer "B.Fab")
		)
		(pad "1" smd rect
			(at 0.2667 0)
			(size 0.3048 0.381)
			(layers "B.Cu" "B.Mask" "B.Paste")
			(net "P1V8_CPU1_RT_1D")
		)
		(pad "2" smd rect
			(at -0.2667 0 180)
			(size 0.3048 0.381)
			(layers "B.Cu" "B.Mask" "B.Paste")
			(net "TEST0_RT_CPU1_P0")
		)
	)
)
